(kicad_pcb
	(version 20221018)
	(generator pcbnew)
	(general
    (thickness 1.518)
  )
	(paper "A4")
	(title_block
    (title "Kria K26 Devboard")
    (date "2024-03-26")
    (rev "1.2.5")
    (comment 1 "www.antmicro.com")
    (comment 2 "Antmicro Ltd.")
		(comment 9 "footprints 298-304 of 660")
	)
	(layers
    (0 "F.Cu" mixed)
    (1 "In1.Cu" power)
    (2 "In2.Cu" mixed)
    (3 "In3.Cu" power)
    (4 "In4.Cu" mixed)
    (5 "In5.Cu" power)
    (6 "In6.Cu" mixed)
    (31 "B.Cu" power)
    (32 "B.Adhes" user "B.Adhesive")
    (33 "F.Adhes" user "F.Adhesive")
    (34 "B.Paste" user)
    (35 "F.Paste" user)
    (36 "B.SilkS" user "B.Silkscreen")
    (37 "F.SilkS" user "F.Silkscreen")
    (38 "B.Mask" user)
    (39 "F.Mask" user)
    (40 "Dwgs.User" user "User.Drawings")
    (41 "Cmts.User" user "User.Comments")
    (42 "Eco1.User" user "User.Eco1")
    (43 "Eco2.User" user "User.Eco2")
    (44 "Edge.Cuts" user)
    (45 "Margin" user)
    (46 "B.CrtYd" user "B.Courtyard")
    (47 "F.CrtYd" user "F.Courtyard")
    (48 "B.Fab" user)
    (49 "F.Fab" user)
  )
	(footprint "kria-k26-devboard-footprints:USB-A_Receptacle_Amphenol_GSB3112311HR" (layer "F.Cu")
    (at 133.25 65.73 180)
    (descr "Ethernet Amphenol")
    (tags "Ethernet Amphenol")
    (property "Author" "Antmicro")
    (property "License" "Apache-2.0")
    (property "MPN" "GSB3112311HR")
    (property "Manufacturer" "Amphenol")
    (property "Sheetfile" "usb.kicad_sch")
    (property "Sheetname" "USB")
    (property "ki_description" "USB-A (USB TYPE-A) USB 3.2 Gen 1 (USB 3.1 Gen 1, Superspeed (USB 3.0)) Receptacle Connector 5 Position Through Hole, Right Angle")
    (property "ki_keywords" "USB, CONNECTOR, THT, HORIZONTAL")
    (attr through_hole)
    (fp_text reference "U24" (at -3.04 -6.99) (layer "F.SilkS")
        (effects (font (size 0.7 0.7) (thickness 0.15)) (justify right bottom))
    )
    (fp_text value "USB-A_Amphenol_GSB3112311HR" (at 0 14.8) (layer "F.Fab") hide
        (effects (font (size 0.7 0.7) (thickness 0.15)) (justify right bottom))
    )
    (fp_text user "Author: Antmicro" (at -4.6 17.501) (layer "F.Fab") hide
        (effects (font (size 0.7 0.7) (thickness 0.15)) (justify right bottom))
    )
    (fp_text user "${REFERENCE}" (at -4.6 16.3) (layer "F.Fab") hide
        (effects (font (size 0.7 0.7) (thickness 0.15)) (justify right bottom))
    )
    (fp_text user "License: Apache-2.0" (at -4.6 18.7) (layer "F.Fab") hide
        (effects (font (size 0.7 0.7) (thickness 0.15)) (justify right bottom))
    )
    (fp_rect (start -4.6 13.711) (end 11.7 -6.6)
      (stroke (width 0.05) (type solid)) (fill none) (layer "F.CrtYd"))
    (pad "1" thru_hole circle (at 0 0 270) (size 1.1 1.1) (drill 0.7) (layers "*.Cu" "*.Mask")
      (net 64 "/USB/USB1_VBUS") (pinfunction "VBUS") (pintype "passive"))
    (pad "2" thru_hole circle (at 2.499 0 270) (size 1.1 1.1) (drill 0.7) (layers "*.Cu" "*.Mask")
      (net 286 "/USB/USB1_TVS_N") (pinfunction "D-") (pintype "bidirectional"))
    (pad "3" thru_hole circle (at 4.498 0 270) (size 1.1 1.1) (drill 0.7) (layers "*.Cu" "*.Mask")
      (net 287 "/USB/USB1_TVS_P") (pinfunction "D+") (pintype "bidirectional"))
    (pad "4" thru_hole circle (at 6.999 0 270) (size 1.1 1.1) (drill 0.7) (layers "*.Cu" "*.Mask")
      (net 1 "GND") (pinfunction "GND") (pintype "power_in"))
    (pad "5" thru_hole circle (at 7.499 -1.499 270) (size 1.1 1.1) (drill 0.7) (layers "*.Cu" "*.Mask")
      (net 83 "/USB/USB1_RX_N") (pinfunction "SSRX-") (pintype "bidirectional"))
    (pad "6" thru_hole circle (at 5.499 -1.499 270) (size 1.1 1.1) (drill 0.7) (layers "*.Cu" "*.Mask")
      (net 84 "/USB/USB1_RX_P") (pinfunction "SSRX+") (pintype "bidirectional"))
    (pad "7" thru_hole circle (at 3.499 -1.499 270) (size 1.1 1.1) (drill 0.7) (layers "*.Cu" "*.Mask")
      (net 1 "GND") (pinfunction "GND_DRAIN") (pintype "power_in"))
    (pad "8" thru_hole circle (at 1.499 -1.499 270) (size 1.1 1.1) (drill 0.7) (layers "*.Cu" "*.Mask")
      (net 278 "/USB/USB1_TX_C_N") (pinfunction "SSTX-") (pintype "bidirectional"))
    (pad "9" thru_hole circle (at -0.5 -1.499 270) (size 1.1 1.1) (drill 0.7) (layers "*.Cu" "*.Mask")
      (net 279 "/USB/USB1_TX_C_P") (pinfunction "SSTX+") (pintype "bidirectional"))
    (pad "10" thru_hole circle (at 0 -3.2 270) (size 1.1 1.1) (drill 0.7) (layers "*.Cu" "*.Mask")
      (net 85 "/USB/USB2_VBUS") (pinfunction "VBUS") (pintype "power_in"))
    (pad "11" thru_hole circle (at 2.499 -3.2 270) (size 1.1 1.1) (drill 0.7) (layers "*.Cu" "*.Mask")
      (net 288 "/USB/USB2_TVS_N") (pinfunction "D-") (pintype "bidirectional"))
    (pad "12" thru_hole circle (at 4.498 -3.2 270) (size 1.1 1.1) (drill 0.7) (layers "*.Cu" "*.Mask")
      (net 289 "/USB/USB2_TVS_P") (pinfunction "D+") (pintype "bidirectional"))
    (pad "13" thru_hole circle (at 6.999 -3.2 270) (size 1.1 1.1) (drill 0.7) (layers "*.Cu" "*.Mask")
      (net 1 "GND") (pinfunction "GND") (pintype "power_in"))
    (pad "14" thru_hole circle (at 7.499 -4.7 270) (size 1.1 1.1) (drill 0.7) (layers "*.Cu" "*.Mask")
      (net 81 "/USB/USB2_RX_N") (pinfunction "SSRX-") (pintype "bidirectional"))
    (pad "15" thru_hole circle (at 5.499 -4.7 270) (size 1.1 1.1) (drill 0.7) (layers "*.Cu" "*.Mask")
      (net 82 "/USB/USB2_RX_P") (pinfunction "SSRX+") (pintype "bidirectional"))
    (pad "16" thru_hole circle (at 3.499 -4.7 270) (size 1.1 1.1) (drill 0.7) (layers "*.Cu" "*.Mask")
      (net 1 "GND") (pinfunction "GND_DRAIN") (pintype "power_in"))
    (pad "17" thru_hole circle (at 1.499 -4.7 270) (size 1.1 1.1) (drill 0.7) (layers "*.Cu" "*.Mask")
      (net 280 "/USB/USB2_TX_C_N") (pinfunction "SSTX-") (pintype "bidirectional"))
    (pad "18" thru_hole circle (at -0.5 -4.7 270) (size 1.1 1.1) (drill 0.7) (layers "*.Cu" "*.Mask")
      (net 281 "/USB/USB2_TX_C_P") (pinfunction "SSTX+") (pintype "bidirectional"))
    (pad "SH" thru_hole circle (at -3.072 -3.68 270) (size 2.9 2.9) (drill 2.3) (layers "*.Cu" "*.Mask")
      (net 319 "SH_UP") (pinfunction "SHIELD") (pintype "passive"))
    (pad "SH" thru_hole circle (at -3.072 2 270) (size 2.9 2.9) (drill 2.3) (layers "*.Cu" "*.Mask")
      (net 319 "SH_UP") (pinfunction "SHIELD") (pintype "passive"))
    (pad "SH" thru_hole circle (at 10.07 -3.68 270) (size 2.9 2.9) (drill 2.3) (layers "*.Cu" "*.Mask")
      (net 319 "SH_UP") (pinfunction "SHIELD") (pintype "passive"))
    (pad "SH" thru_hole circle (at 10.169 2 270) (size 2.9 2.9) (drill 2.3) (layers "*.Cu" "*.Mask")
      (net 319 "SH_UP") (pinfunction "SHIELD") (pintype "passive"))
  )
	(footprint "kria-k26-devboard-footprints:SW_KMR211NGLFS_SMD" (layer "F.Cu")
    (at 95.2 150.1)
    (property "Author" "Antmicro")
    (property "License" "Apache-2.0")
    (property "MPN" "KMR211NGLFS")
    (property "Manufacturer" "C&K")
    (property "Sheetfile" "reset.kicad_sch")
    (property "Sheetname" "Reset logic")
    (property "ki_description" "Tactile Switch, KMR 2 Series, Top Actuated, Surface Mount, Oval Button, 120 gf, 50mA at 32VDC")
    (property "ki_keywords" "VERTICAL, SMT, SWITCH, MECHANICAL, TACTILE")
    (attr smd)
    (fp_text reference "S1" (at -3.88 -1.22) (layer "F.SilkS")
        (effects (font (size 0.7 0.7) (thickness 0.15)) (justify left bottom))
    )
    (fp_text value "SW_KMR211NGLFS_SMD" (at -3 3) (layer "F.Fab") hide
        (effects (font (size 0.7 0.7) (thickness 0.15)) (justify left bottom))
    )
    (fp_text user "License: Apache-2.0" (at -3 6.75) (layer "F.Fab") hide
        (effects (font (size 0.7 0.7) (thickness 0.15)) (justify left bottom))
    )
    (fp_text user "Author: Antmicro" (at -3 5.5) (layer "F.Fab") hide
        (effects (font (size 0.7 0.7) (thickness 0.15)) (justify left bottom))
    )
    (fp_text user "${REFERENCE}" (at -3 4.25) (layer "F.Fab") hide
        (effects (font (size 0.7 0.7) (thickness 0.15)) (justify left bottom))
    )
    (fp_line (start -2.1 -1.6) (end -2.1 -1.499)
      (stroke (width 0.15) (type solid)) (layer "F.SilkS"))
    (fp_line (start -2.1 1.601) (end -2.1 1.48)
      (stroke (width 0.15) (type solid)) (layer "F.SilkS"))
    (fp_line (start 2.101 -1.6) (end -2.1 -1.6)
      (stroke (width 0.15) (type solid)) (layer "F.SilkS"))
    (fp_line (start 2.101 -1.58) (end 2.101 -1.459)
      (stroke (width 0.15) (type solid)) (layer "F.SilkS"))
    (fp_line (start 2.101 1.601) (end -2.1 1.601)
      (stroke (width 0.15) (type solid)) (layer "F.SilkS"))
    (fp_line (start 2.101 1.601) (end 2.101 1.48)
      (stroke (width 0.15) (type solid)) (layer "F.SilkS"))
    (fp_rect (start 2.751 1.75) (end -2.748 -1.749)
      (stroke (width 0.05) (type solid)) (fill none) (layer "F.CrtYd"))
    (fp_line (start -2.1 -1.6) (end -2.1 1.601)
      (stroke (width 0.15) (type solid)) (layer "F.Fab"))
    (fp_line (start -2.1 1.601) (end 2.101 1.601)
      (stroke (width 0.15) (type solid)) (layer "F.Fab"))
    (fp_line (start -0.248 -0.8) (end 0.25 -0.8)
      (stroke (width 0.15) (type solid)) (layer "F.Fab"))
    (fp_line (start 0.25 0.802) (end -0.248 0.802)
      (stroke (width 0.15) (type solid)) (layer "F.Fab"))
    (fp_line (start 2.101 -1.6) (end -2.1 -1.6)
      (stroke (width 0.15) (type solid)) (layer "F.Fab"))
    (fp_line (start 2.101 1.601) (end 2.101 -1.6)
      (stroke (width 0.15) (type solid)) (layer "F.Fab"))
    (fp_arc (start -0.248 0.802) (mid -1.050001 0.001) (end -0.248 -0.8)
      (stroke (width 0.15) (type solid)) (layer "F.Fab"))
    (fp_arc (start 0.25 -0.8) (mid 1.051001 0.001) (end 0.25 0.802)
      (stroke (width 0.15) (type solid)) (layer "F.Fab"))
    (pad "1" smd rect (at -2.048 -0.8 180) (size 0.9 1) (layers "F.Cu" "F.Paste" "F.Mask")
      (net 1 "GND") (pinfunction "1") (pintype "passive"))
    (pad "2" smd rect (at 2.05 -0.8 180) (size 0.9 1) (layers "F.Cu" "F.Paste" "F.Mask")
      (net 1 "GND") (pinfunction "2") (pintype "passive"))
    (pad "3" smd rect (at -2.048 0.802 180) (size 0.9 1) (layers "F.Cu" "F.Paste" "F.Mask")
      (net 327 "Net-(D4-PadK)") (pinfunction "3") (pintype "passive"))
    (pad "4" smd rect (at 2.05 0.802 180) (size 0.9 1) (layers "F.Cu" "F.Paste" "F.Mask")
      (net 327 "Net-(D4-PadK)") (pinfunction "4") (pintype "passive"))
  )
	(footprint "kria-k26-devboard-footprints:TP_SMD_0.75mm" (layer "F.Cu")
    (at 111.3 146.5)
    (property "Author" "Antmicro")
    (property "License" "Apache-2.0")
    (property "MPN" "")
    (property "Manufacturer" "")
    (property "Sheetfile" "reset.kicad_sch")
    (property "Sheetname" "Reset logic")
    (property "ki_description" "Test Point 0.75mm")
    (attr exclude_from_pos_files)
    (fp_text reference "TP19" (at 7.33 0.86 90) (layer "F.SilkS")
        (effects (font (size 0.7 0.7) (thickness 0.15)) (justify left bottom))
    )
    (fp_text value "TP_0.75mm_SMD" (at 0 1.2) (layer "F.Fab") hide
        (effects (font (size 0.7 0.7) (thickness 0.15)) (justify left bottom))
    )
    (fp_text user "${REFERENCE}" (at -0.4 2.7) (layer "F.Fab") hide
        (effects (font (size 0.7 0.7) (thickness 0.15)) (justify left bottom))
    )
    (fp_text user "License: Apache-2.0" (at -0.4 5.101) (layer "F.Fab") hide
        (effects (font (size 0.7 0.7) (thickness 0.15)) (justify left bottom))
    )
    (fp_text user "Author: Antmicro" (at -0.4 3.901) (layer "F.Fab") hide
        (effects (font (size 0.7 0.7) (thickness 0.15)) (justify left bottom))
    )
    (pad "1" smd circle (at 0 0) (size 0.75 0.75) (layers "F.Cu" "F.Mask")
      (net 175 "/Reset logic/~{USB_HUB_RESET}") (pinfunction "1") (pintype "passive"))
  )
	(footprint "kria-k26-devboard-footprints:DFN-8-1EP_3x2mm_P0.5mm_EP1.36x1.46mm" (layer "F.Cu")
    (at 104.65 134.65 -90)
    (property "Author" "Antmicro")
    (property "License" "Apache-2.0")
    (property "MPN" "M24C64-FMC6TG")
    (property "Manufacturer" "STMicroelectronics")
    (property "Sheetfile" "i2c.kicad_sch")
    (property "Sheetname" "I2C ")
    (property "ki_description" "EEPROM, 8K x 8bit, Serial I2C (2-Wire), 1 MHz, UFDFPN, 8 Pins")
    (property "ki_keywords" "SMT, MEMORY, IC, STORAGE, I2C")
    (attr smd)
    (fp_text reference "U13" (at 1.1 -2.11 -90) (layer "F.SilkS")
        (effects (font (size 0.7 0.7) (thickness 0.15)) (justify left bottom))
    )
    (fp_text value "M24C64-F_DFN8" (at 0 2.2 -90) (layer "F.Fab")
        (effects (font (size 0.7 0.7) (thickness 0.15)) (justify left bottom))
    )
    (fp_text user "License: Apache-2.0" (at -2.27 6.453 -90) (layer "F.Fab") hide
        (effects (font (size 0.7 0.7) (thickness 0.15)) (justify left bottom))
    )
    (fp_text user "${REFERENCE}" (at -2.27 4.052 -90) (layer "F.Fab") hide
        (effects (font (size 0.7 0.7) (thickness 0.15)) (justify left bottom))
    )
    (fp_text user "Author: Antmicro" (at -2.27 5.253 -90) (layer "F.Fab") hide
        (effects (font (size 0.7 0.7) (thickness 0.15)) (justify left bottom))
    )
    (fp_line (start -1.501 1.111) (end 1.518 1.111)
      (stroke (width 0.15) (type solid)) (layer "F.SilkS"))
    (fp_line (start 1.498 -1.12) (end -1.511 -1.12)
      (stroke (width 0.15) (type solid)) (layer "F.SilkS"))
    (fp_circle (center -1.751 -1.05) (end -1.7 -1.05)
      (stroke (width 0.15) (type solid)) (fill solid) (layer "F.SilkS"))
    (fp_line (start -1.901 -1.262) (end 1.889 -1.262)
      (stroke (width 0.05) (type solid)) (layer "F.CrtYd"))
    (fp_line (start -1.901 1.228) (end -1.901 -1.262)
      (stroke (width 0.05) (type solid)) (layer "F.CrtYd"))
    (fp_line (start 1.889 -1.262) (end 1.889 1.228)
      (stroke (width 0.05) (type solid)) (layer "F.CrtYd"))
    (fp_line (start 1.889 1.228) (end -1.901 1.228)
      (stroke (width 0.05) (type solid)) (layer "F.CrtYd"))
    (fp_line (start -1.501 0.99) (end -1.501 -0.989)
      (stroke (width 0.15) (type solid)) (layer "F.Fab"))
    (fp_line (start 1.498 -0.999) (end -1.491 -0.999)
      (stroke (width 0.15) (type solid)) (layer "F.Fab"))
    (fp_line (start 1.498 -0.999) (end 1.498 0.99)
      (stroke (width 0.15) (type solid)) (layer "F.Fab"))
    (fp_line (start 1.498 0.999) (end -1.501 0.999)
      (stroke (width 0.15) (type solid)) (layer "F.Fab"))
    (pad "1" smd rect (at -1.451 -0.749 180) (size 0.3 0.7) (layers "F.Cu" "F.Paste" "F.Mask")
      (net 15 "PS_3V3") (pinfunction "E0") (pintype "input"))
    (pad "2" smd rect (at -1.451 -0.25 180) (size 0.3 0.7) (layers "F.Cu" "F.Paste" "F.Mask")
      (net 1 "GND") (pinfunction "E1") (pintype "input"))
    (pad "3" smd rect (at -1.451 0.249 180) (size 0.3 0.7) (layers "F.Cu" "F.Paste" "F.Mask")
      (net 1 "GND") (pinfunction "E2") (pintype "input"))
    (pad "4" smd rect (at -1.451 0.75 180) (size 0.3 0.7) (layers "F.Cu" "F.Paste" "F.Mask")
      (net 1 "GND") (pinfunction "VSS") (pintype "power_in"))
    (pad "5" smd rect (at 1.448 0.75 180) (size 0.3 0.7) (layers "F.Cu" "F.Paste" "F.Mask")
      (net 163 "/I2C /I2C_SDA_3V3") (pinfunction "SDA") (pintype "bidirectional"))
    (pad "6" smd rect (at 1.448 0.249 180) (size 0.3 0.7) (layers "F.Cu" "F.Paste" "F.Mask")
      (net 162 "/I2C /I2C_SCK_3V3") (pinfunction "SCL") (pintype "input"))
    (pad "7" smd rect (at 1.448 -0.25 180) (size 0.3 0.7) (layers "F.Cu" "F.Paste" "F.Mask")
      (net 186 "/Debug and JTAG/~{EEPROM_WC}") (pinfunction "~{WC}") (pintype "input"))
    (pad "8" smd rect (at 1.448 -0.749 180) (size 0.3 0.7) (layers "F.Cu" "F.Paste" "F.Mask")
      (net 15 "PS_3V3") (pinfunction "VCC") (pintype "power_in"))
    (pad "9" smd rect (at 0 0 180) (size 1.5 1.7) (layers "F.Cu" "F.Paste" "F.Mask")
      (net 1 "GND") (pinfunction "VSS") (pintype "passive") (solder_paste_margin_ratio -0.1))
  )
	(footprint "kria-k26-devboard-footprints:TP_SMD_0.75mm" (layer "F.Cu")
    (at 185.4 114.8)
    (property "Author" "Antmicro")
    (property "License" "Apache-2.0")
    (property "MPN" "")
    (property "Manufacturer" "")
    (property "Sheetfile" "PoE.kicad_sch")
    (property "Sheetname" "PoE")
    (property "ki_description" "Test Point 0.75mm")
    (attr exclude_from_pos_files)
    (fp_text reference "TP35" (at -2.63 -0.39 180) (layer "F.SilkS")
        (effects (font (size 0.7 0.7) (thickness 0.15)) (justify left bottom))
    )
    (fp_text value "TP_0.75mm_SMD" (at 0 1.2) (layer "F.Fab") hide
        (effects (font (size 0.7 0.7) (thickness 0.15)) (justify left bottom))
    )
    (fp_text user "License: Apache-2.0" (at -0.4 5.101) (layer "F.Fab") hide
        (effects (font (size 0.7 0.7) (thickness 0.15)) (justify left bottom))
    )
    (fp_text user "Author: Antmicro" (at -0.4 3.901) (layer "F.Fab") hide
        (effects (font (size 0.7 0.7) (thickness 0.15)) (justify left bottom))
    )
    (fp_text user "${REFERENCE}" (at -0.4 2.7) (layer "F.Fab") hide
        (effects (font (size 0.7 0.7) (thickness 0.15)) (justify left bottom))
    )
    (pad "1" smd circle (at 0 0) (size 0.75 0.75) (layers "F.Cu" "F.Mask")
      (net 13 "/Power Supply/PoE/POE_12V") (pinfunction "1") (pintype "passive"))
  )
	(footprint "kria-k26-devboard-footprints:TP_SMD_0.75mm" (layer "F.Cu")
    (at 184.6 87.2)
    (property "Author" "Antmicro")
    (property "License" "Apache-2.0")
    (property "MPN" "")
    (property "Manufacturer" "")
    (property "Sheetfile" "PoE.kicad_sch")
    (property "Sheetname" "PoE")
    (property "ki_description" "Test Point 0.75mm")
    (attr exclude_from_pos_files)
    (fp_text reference "TP34" (at 0.3 0.42) (layer "F.SilkS")
        (effects (font (size 0.7 0.7) (thickness 0.15)) (justify left bottom))
    )
    (fp_text value "TP_0.75mm_SMD" (at 0 1.2) (layer "F.Fab") hide
        (effects (font (size 0.7 0.7) (thickness 0.15)) (justify left bottom))
    )
    (fp_text user "License: Apache-2.0" (at -0.4 5.101) (layer "F.Fab") hide
        (effects (font (size 0.7 0.7) (thickness 0.15)) (justify left bottom))
    )
    (fp_text user "Author: Antmicro" (at -0.4 3.901) (layer "F.Fab") hide
        (effects (font (size 0.7 0.7) (thickness 0.15)) (justify left bottom))
    )
    (fp_text user "${REFERENCE}" (at -0.4 2.7) (layer "F.Fab") hide
        (effects (font (size 0.7 0.7) (thickness 0.15)) (justify left bottom))
    )
    (pad "1" smd circle (at 0 0) (size 0.75 0.75) (layers "F.Cu" "F.Mask")
      (net 9 "/Power Supply/PoE/VDD_POE_IN") (pinfunction "1") (pintype "passive"))
  )
	(footprint "kria-k26-devboard-footprints:TP_SMD_0.75mm" (layer "F.Cu")
    (at 151 70.65)
    (property "Author" "Antmicro")
    (property "License" "Apache-2.0")
    (property "MPN" "")
    (property "Manufacturer" "")
    (property "Sheetfile" "usbc-socket.kicad_sch")
    (property "Sheetname" "USB-C socket")
    (property "ki_description" "Test Point 0.75mm")
    (attr exclude_from_pos_files)
    (fp_text reference "TP45" (at -1.98 1.3) (layer "F.SilkS")
        (effects (font (size 0.7 0.7) (thickness 0.15)) (justify left bottom))
    )
    (fp_text value "TP_0.75mm_SMD" (at 0 1.2) (layer "F.Fab") hide
        (effects (font (size 0.7 0.7) (thickness 0.15)) (justify left bottom))
    )
    (fp_text user "Author: Antmicro" (at -0.4 3.901) (layer "F.Fab") hide
        (effects (font (size 0.7 0.7) (thickness 0.15)) (justify left bottom))
    )
    (fp_text user "License: Apache-2.0" (at -0.4 5.101) (layer "F.Fab") hide
        (effects (font (size 0.7 0.7) (thickness 0.15)) (justify left bottom))
    )
    (fp_text user "${REFERENCE}" (at -0.4 2.7) (layer "F.Fab") hide
        (effects (font (size 0.7 0.7) (thickness 0.15)) (justify left bottom))
    )
    (pad "1" smd circle (at 0 0) (size 0.75 0.75) (layers "F.Cu" "F.Mask")
      (net 229 "/Debug and JTAG/PD_EN") (pinfunction "1") (pintype "passive"))
  )
)
